(kicad_pcb
	(version 20241229)
	(generator "pcbnew")
	(generator_version "9.0")
	(general
		(thickness 1.63)
		(legacy_teardrops no)
	)
	(paper "A4")
	(title_block
		(title "CM4 Baseboard")
		(date "2026-01-05")
		(rev "1.1.1")
		(company "Antmicro Ltd")
		(comment 1 "www.antmicro.com")
		(comment 9 "footprints 129-133 of 506")
	)
	(layers
		(0 "F.Cu" signal)
		(4 "In1.Cu" power)
		(6 "In2.Cu" power)
		(8 "In3.Cu" signal)
		(10 "In4.Cu" signal)
		(2 "B.Cu" signal)
		(9 "F.Adhes" user "F.Adhesive")
		(11 "B.Adhes" user "B.Adhesive")
		(13 "F.Paste" user)
		(15 "B.Paste" user)
		(5 "F.SilkS" user "F.Silkscreen")
		(7 "B.SilkS" user "B.Silkscreen")
		(1 "F.Mask" user)
		(3 "B.Mask" user)
		(17 "Dwgs.User" user "User.Drawings")
		(19 "Cmts.User" user "User.Comments")
		(21 "Eco1.User" user "User.Eco1")
		(23 "Eco2.User" user "User.Eco2")
		(25 "Edge.Cuts" user)
		(27 "Margin" user)
		(31 "F.CrtYd" user "F.Courtyard")
		(29 "B.CrtYd" user "B.Courtyard")
		(35 "F.Fab" user)
		(33 "B.Fab" user)
	)
	(footprint "antmicro-footprints:C_0402_1005Metric"
		(layer "F.Cu")
		(at 86.642962 143.557236 180)
		(descr "Capacitor SMD 0402")
		(tags "capacitor SMD 0402")
		(property "Reference" "C912"
			(at 0.875 -0.419264 0)
			(layer "F.SilkS")
			(effects
				(font
					(size 0.7 0.7)
					(thickness 0.15)
				)
				(justify right bottom)
			)
		)
		(property "Value" "C_100n_0402"
			(at -1.022927 2.155213 0)
			(layer "F.Fab")
			(effects
				(font
					(size 0.7 0.7)
					(thickness 0.15)
				)
				(justify right bottom)
			)
		)
		(property "Datasheet" "https://www.murata.com/products/productdetail?partno=GRM155R61H104KE14%23"
			(at 0 0 180)
			(layer "F.Fab")
			(hide yes)
			(effects
				(font
					(size 1.27 1.27)
					(thickness 0.15)
				)
			)
		)
		(property "Manufacturer" "Murata"
			(at 0 0 180)
			(unlocked yes)
			(layer "F.Fab")
			(hide yes)
			(effects
				(font
					(size 1 1)
					(thickness 0.15)
				)
			)
		)
		(property "MPN" "GRM155R61H104KE14D"
			(at 0 0 180)
			(unlocked yes)
			(layer "F.Fab")
			(hide yes)
			(effects
				(font
					(size 1 1)
					(thickness 0.15)
				)
			)
		)
		(property "Val" "100n"
			(at 0 0 180)
			(unlocked yes)
			(layer "F.Fab")
			(hide yes)
			(effects
				(font
					(size 1 1)
					(thickness 0.15)
				)
			)
		)
		(property "License" "Apache-2.0"
			(at 0 0 180)
			(unlocked yes)
			(layer "F.Fab")
			(hide yes)
			(effects
				(font
					(size 1 1)
					(thickness 0.15)
				)
			)
		)
		(property "Author" "Antmicro"
			(at 0 0 180)
			(unlocked yes)
			(layer "F.Fab")
			(hide yes)
			(effects
				(font
					(size 1 1)
					(thickness 0.15)
				)
			)
		)
		(property "Voltage" "50V"
			(at 0 0 180)
			(unlocked yes)
			(layer "F.Fab")
			(hide yes)
			(effects
				(font
					(size 1 1)
					(thickness 0.15)
				)
			)
		)
		(property "Dielectric" "X5R"
			(at 0 0 180)
			(unlocked yes)
			(layer "F.Fab")
			(hide yes)
			(effects
				(font
					(size 1 1)
					(thickness 0.15)
				)
			)
		)
		(sheetname "/USB/")
		(sheetfile "usb.kicad_sch")
		(attr smd)
		(fp_rect
			(start -0.925 -0.47)
			(end 0.925 0.47)
			(stroke
				(width 0.05)
				(type default)
			)
			(fill no)
			(layer "F.CrtYd")
		)
		(fp_line
			(start 0.504 0.248)
			(end -0.494 0.248)
			(stroke
				(width 0.15)
				(type solid)
			)
			(layer "F.Fab")
		)
		(fp_line
			(start 0.504 -0.25)
			(end 0.504 0.248)
			(stroke
				(width 0.15)
				(type solid)
			)
			(layer "F.Fab")
		)
		(fp_line
			(start -0.494 0.248)
			(end -0.494 -0.25)
			(stroke
				(width 0.15)
				(type solid)
			)
			(layer "F.Fab")
		)
		(fp_line
			(start -0.494 -0.25)
			(end 0.504 -0.25)
			(stroke
				(width 0.15)
				(type solid)
			)
			(layer "F.Fab")
		)
		(fp_text user "Author: Antmicro"
			(at -0.939 3.399 180)
			(layer "F.Fab")
			(effects
				(font
					(size 0.7 0.7)
					(thickness 0.15)
				)
				(justify left bottom)
			)
		)
		(fp_text user "License: Apache-2.0"
			(at -0.939 5.799 180)
			(layer "F.Fab")
			(effects
				(font
					(size 0.7 0.7)
					(thickness 0.15)
				)
				(justify left bottom)
			)
		)
		(fp_text user "${REFERENCE}"
			(at -0.939 4.599 180)
			(layer "F.Fab")
			(effects
				(font
					(size 0.7 0.7)
					(thickness 0.15)
				)
				(justify left bottom)
			)
		)
		(pad "1" smd roundrect
			(at -0.48 0 180)
			(size 0.59 0.64)
			(layers "F.Cu" "F.Mask" "F.Paste")
			(roundrect_rratio 0.25)
			(net 30 "/USB/USB_1V2")
			(pintype "passive")
		)
		(pad "2" smd roundrect
			(at 0.48 0 180)
			(size 0.59 0.64)
			(layers "F.Cu" "F.Mask" "F.Paste")
			(roundrect_rratio 0.25)
			(net 3 "GND")
			(pintype "passive")
		)
	)
	(footprint "antmicro-footprints:TP_SMD_0.75mm"
		(layer "F.Cu")
		(at 90.75 121.65)
		(property "Reference" "TP921"
			(at 0.5 3.625 90)
			(layer "F.SilkS")
			(effects
				(font
					(size 0.7 0.7)
					(thickness 0.15)
				)
				(justify left bottom)
			)
		)
		(property "Value" "TP_0.75mm_SMD"
			(at 0 1.2 0)
			(layer "F.Fab")
			(effects
				(font
					(size 0.7 0.7)
					(thickness 0.15)
				)
				(justify left bottom)
			)
		)
		(property "MPN" ""
			(at 0 0 0)
			(unlocked yes)
			(layer "F.Fab")
			(hide yes)
			(effects
				(font
					(size 1 1)
					(thickness 0.15)
				)
			)
		)
		(property "Manufacturer" ""
			(at 0 0 0)
			(unlocked yes)
			(layer "F.Fab")
			(hide yes)
			(effects
				(font
					(size 1 1)
					(thickness 0.15)
				)
			)
		)
		(property "Author" "Antmicro"
			(at 0 0 0)
			(unlocked yes)
			(layer "F.Fab")
			(hide yes)
			(effects
				(font
					(size 1 1)
					(thickness 0.15)
				)
			)
		)
		(property "License" "Apache-2.0"
			(at 0 0 0)
			(unlocked yes)
			(layer "F.Fab")
			(hide yes)
			(effects
				(font
					(size 1 1)
					(thickness 0.15)
				)
			)
		)
		(sheetname "/USB/")
		(sheetfile "usb.kicad_sch")
		(attr exclude_from_pos_files exclude_from_bom)
		(fp_circle
			(center 0 0)
			(end 0.475 0)
			(stroke
				(width 0.05)
				(type default)
			)
			(fill no)
			(layer "F.CrtYd")
		)
		(fp_text user "License: Apache-2.0"
			(at -0.4 5.101 0)
			(layer "F.Fab")
			(effects
				(font
					(size 0.7 0.7)
					(thickness 0.15)
				)
				(justify left bottom)
			)
		)
		(fp_text user "Author: Antmicro"
			(at -0.4 3.901 0)
			(layer "F.Fab")
			(effects
				(font
					(size 0.7 0.7)
					(thickness 0.15)
				)
				(justify left bottom)
			)
		)
		(fp_text user "${REFERENCE}"
			(at -0.4 2.7 0)
			(layer "F.Fab")
			(effects
				(font
					(size 0.7 0.7)
					(thickness 0.15)
				)
				(justify left bottom)
			)
		)
		(pad "1" smd circle
			(at 0 0)
			(size 0.75 0.75)
			(layers "F.Cu" "F.Mask")
			(net 24 "/Compute module/USBA_VBUS")
			(pinfunction "1")
			(pintype "passive")
		)
	)
	(footprint "antmicro-footprints:TP_SMD_0.75mm"
		(layer "F.Cu")
		(at 81.3 137.65)
		(property "Reference" "TP917"
			(at -1.725 3.92 90)
			(layer "F.SilkS")
			(effects
				(font
					(size 0.7 0.7)
					(thickness 0.15)
				)
				(justify left bottom)
			)
		)
		(property "Value" "TP_0.75mm_SMD"
			(at 0 1.2 0)
			(layer "F.Fab")
			(effects
				(font
					(size 0.7 0.7)
					(thickness 0.15)
				)
				(justify left bottom)
			)
		)
		(property "MPN" ""
			(at 0 0 0)
			(unlocked yes)
			(layer "F.Fab")
			(hide yes)
			(effects
				(font
					(size 1 1)
					(thickness 0.15)
				)
			)
		)
		(property "Manufacturer" ""
			(at 0 0 0)
			(unlocked yes)
			(layer "F.Fab")
			(hide yes)
			(effects
				(font
					(size 1 1)
					(thickness 0.15)
				)
			)
		)
		(property "Author" "Antmicro"
			(at 0 0 0)
			(unlocked yes)
			(layer "F.Fab")
			(hide yes)
			(effects
				(font
					(size 1 1)
					(thickness 0.15)
				)
			)
		)
		(property "License" "Apache-2.0"
			(at 0 0 0)
			(unlocked yes)
			(layer "F.Fab")
			(hide yes)
			(effects
				(font
					(size 1 1)
					(thickness 0.15)
				)
			)
		)
		(sheetname "/USB/")
		(sheetfile "usb.kicad_sch")
		(attr exclude_from_pos_files exclude_from_bom)
		(fp_circle
			(center 0 0)
			(end 0.475 0)
			(stroke
				(width 0.05)
				(type default)
			)
			(fill no)
			(layer "F.CrtYd")
		)
		(fp_text user "Author: Antmicro"
			(at -0.4 3.901 0)
			(layer "F.Fab")
			(effects
				(font
					(size 0.7 0.7)
					(thickness 0.15)
				)
				(justify left bottom)
			)
		)
		(fp_text user "License: Apache-2.0"
			(at -0.4 5.101 0)
			(layer "F.Fab")
			(effects
				(font
					(size 0.7 0.7)
					(thickness 0.15)
				)
				(justify left bottom)
			)
		)
		(fp_text user "${REFERENCE}"
			(at -0.4 2.7 0)
			(layer "F.Fab")
			(effects
				(font
					(size 0.7 0.7)
					(thickness 0.15)
				)
				(justify left bottom)
			)
		)
		(pad "1" smd circle
			(at 0 0)
			(size 0.75 0.75)
			(layers "F.Cu" "F.Mask")
			(net 442 "Net-(U905-GPIO5)")
			(pinfunction "1")
			(pintype "passive")
		)
	)
	(footprint "antmicro-footprints:Resonator_SMD_Abracon_ABM8G_3.2x2.5mm"
		(layer "F.Cu")
		(at 89.642962 147.1665 -90)
		(property "Reference" "Y901"
			(at 2.85 1.425 180)
			(layer "F.SilkS")
			(effects
				(font
					(size 0.7 0.7)
					(thickness 0.15)
				)
				(justify left bottom)
			)
		)
		(property "Value" "Resonator_12MHz_ABM8G"
			(at -1.75 2.548 270)
			(layer "F.Fab")
			(effects
				(font
					(size 0.7 0.7)
					(thickness 0.15)
				)
				(justify left bottom)
			)
		)
		(property "Datasheet" "https://abracon.com/Resonators/ABM8G.pdf"
			(at 0 0 270)
			(layer "F.Fab")
			(hide yes)
			(effects
				(font
					(size 1.27 1.27)
					(thickness 0.15)
				)
			)
		)
		(property "MPN" "ABM8G-12.000MHZ-18-D2Y-T"
			(at 0 0 270)
			(unlocked yes)
			(layer "F.Fab")
			(hide yes)
			(effects
				(font
					(size 1 1)
					(thickness 0.15)
				)
			)
		)
		(property "Manufacturer" "Abracon"
			(at 0 0 270)
			(unlocked yes)
			(layer "F.Fab")
			(hide yes)
			(effects
				(font
					(size 1 1)
					(thickness 0.15)
				)
			)
		)
		(property "Val" "12 MHz"
			(at 0 0 270)
			(unlocked yes)
			(layer "F.Fab")
			(hide yes)
			(effects
				(font
					(size 1 1)
					(thickness 0.15)
				)
			)
		)
		(property "Author" "Antmicro"
			(at 0 0 270)
			(unlocked yes)
			(layer "F.Fab")
			(hide yes)
			(effects
				(font
					(size 1 1)
					(thickness 0.15)
				)
			)
		)
		(property "License" "Apache-2.0"
			(at 0 0 270)
			(unlocked yes)
			(layer "F.Fab")
			(hide yes)
			(effects
				(font
					(size 1 1)
					(thickness 0.15)
				)
			)
		)
		(sheetname "/USB/")
		(sheetfile "usb.kicad_sch")
		(attr smd)
		(fp_line
			(start -0.35 1.25)
			(end 0.45 1.25)
			(stroke
				(width 0.15)
				(type solid)
			)
			(layer "F.SilkS")
		)
		(fp_line
			(start -1.6 0.3)
			(end -1.6 -0.2)
			(stroke
				(width 0.15)
				(type solid)
			)
			(layer "F.SilkS")
		)
		(fp_line
			(start 1.6 0.3)
			(end 1.6 -0.2)
			(stroke
				(width 0.15)
				(type solid)
			)
			(layer "F.SilkS")
		)
		(fp_line
			(start -0.35 -1.25)
			(end 0.45 -1.25)
			(stroke
				(width 0.15)
				(type solid)
			)
			(layer "F.SilkS")
		)
		(fp_circle
			(center -1.75 1.5)
			(end -1.7 1.5)
			(stroke
				(width 0.15)
				(type solid)
			)
			(fill no)
			(layer "F.SilkS")
		)
		(fp_rect
			(start -1.907 -1.55)
			(end 2.006 1.649)
			(stroke
				(width 0.05)
				(type solid)
			)
			(fill no)
			(layer "F.CrtYd")
		)
		(fp_text user "${REFERENCE}"
			(at -1.75 3.75 270)
			(layer "F.Fab")
			(effects
				(font
					(size 0.7 0.7)
					(thickness 0.15)
				)
				(justify left bottom)
			)
		)
		(fp_text user "License: Apache-2.0"
			(at -1.75 6.5 270)
			(layer "F.Fab")
			(effects
				(font
					(size 0.7 0.7)
					(thickness 0.15)
				)
				(justify left bottom)
			)
		)
		(fp_text user "Author: Antmicro"
			(at -1.75 5 270)
			(layer "F.Fab")
			(effects
				(font
					(size 0.7 0.7)
					(thickness 0.15)
				)
				(justify left bottom)
			)
		)
		(pad "1" smd roundrect
			(at -1.101 0.949 270)
			(size 1.3 1.1)
			(layers "F.Cu" "F.Mask" "F.Paste")
			(roundrect_rratio 0)
			(chamfer_ratio 0.2)
			(chamfer bottom_left)
			(net 114 "Net-(U905-OSCI)")
			(pintype "passive")
		)
		(pad "2" smd rect
			(at 1.199 0.949 270)
			(size 1.3 1.1)
			(layers "F.Cu" "F.Mask" "F.Paste")
			(net 3 "GND")
			(pinfunction "SH")
			(pintype "passive")
		)
		(pad "3" smd rect
			(at 1.199 -0.85 270)
			(size 1.3 1.1)
			(layers "F.Cu" "F.Mask" "F.Paste")
			(net 115 "Net-(U905-OSCO)")
			(pintype "passive")
		)
		(pad "4" smd rect
			(at -1.101 -0.85 270)
			(size 1.3 1.1)
			(layers "F.Cu" "F.Mask" "F.Paste")
			(net 3 "GND")
			(pinfunction "SH")
			(pintype "passive")
		)
	)
	(footprint "antmicro-footprints:SOT-523"
		(layer "F.Cu")
		(at 102.467962 146.2665 -90)
		(property "Reference" "Q905"
			(at -1.2 -2 90)
			(layer "F.SilkS")
			(effects
				(font
					(size 0.7 0.7)
					(thickness 0.15)
				)
				(justify right bottom)
			)
		)
		(property "Value" "PJE138K"
			(at 0.1 1.824 90)
			(layer "F.Fab")
			(effects
				(font
					(size 0.7 0.7)
					(thickness 0.15)
				)
				(justify right bottom)
			)
		)
		(property "Datasheet" "https://www.mouser.com/datasheet/2/1057/PJE138K-1876698.pdf"
			(at 0 0 270)
			(layer "F.Fab")
			(hide yes)
			(effects
				(font
					(size 1.27 1.27)
					(thickness 0.15)
				)
			)
		)
		(property "MPN" "PJE138K_R1_00001"
			(at 0 0 270)
			(unlocked yes)
			(layer "F.Fab")
			(hide yes)
			(effects
				(font
					(size 1 1)
					(thickness 0.15)
				)
			)
		)
		(property "Manufacturer" "PANJIT"
			(at 0 0 270)
			(unlocked yes)
			(layer "F.Fab")
			(hide yes)
			(effects
				(font
					(size 1 1)
					(thickness 0.15)
				)
			)
		)
		(property "Author" "Antmicro"
			(at 0 0 270)
			(unlocked yes)
			(layer "F.Fab")
			(hide yes)
			(effects
				(font
					(size 1 1)
					(thickness 0.15)
				)
			)
		)
		(property "License" "Apache-2.0"
			(at 0 0 270)
			(unlocked yes)
			(layer "F.Fab")
			(hide yes)
			(effects
				(font
					(size 1 1)
					(thickness 0.15)
				)
			)
		)
		(sheetname "/USB/")
		(sheetfile "usb.kicad_sch")
		(attr smd)
		(fp_line
			(start -0.927 -0.051)
			(end -0.927 -0.351)
			(stroke
				(width 0.15)
				(type solid)
			)
			(layer "F.SilkS")
		)
		(fp_line
			(start -0.927 -0.351)
			(end -0.725 -0.551)
			(stroke
				(width 0.15)
				(type solid)
			)
			(layer "F.SilkS")
		)
		(fp_line
			(start -0.725 -0.551)
			(end -0.277 -0.551)
			(stroke
				(width 0.15)
				(type solid)
			)
			(layer "F.SilkS")
		)
		(fp_line
			(start -0.277 -0.551)
			(end -0.277 -0.75)
			(stroke
				(width 0.15)
				(type solid)
			)
			(layer "F.SilkS")
		)
		(fp_circle
			(center -0.9652 0.9652)
			(end -0.9152 0.9652)
			(stroke
				(width 0.15)
				(type solid)
			)
			(fill yes)
			(layer "F.SilkS")
		)
		(fp_line
			(start -1.12 1.15)
			(end 1.1 1.15)
			(stroke
				(width 0.05)
				(type solid)
			)
			(layer "F.CrtYd")
		)
		(fp_line
			(start -1.12 -1.16)
			(end -1.12 1.15)
			(stroke
				(width 0.05)
				(type solid)
			)
			(layer "F.CrtYd")
		)
		(fp_line
			(start -1.12 -1.16)
			(end 1.1 -1.16)
			(stroke
				(width 0.05)
				(type solid)
			)
			(layer "F.CrtYd")
		)
		(fp_line
			(start 1.1 -1.16)
			(end 1.1 1.15)
			(stroke
				(width 0.05)
				(type solid)
			)
			(layer "F.CrtYd")
		)
		(fp_line
			(start 0.8 0.424)
			(end -0.802 0.424)
			(stroke
				(width 0.15)
				(type solid)
			)
			(layer "F.Fab")
		)
		(fp_line
			(start -0.802 -0.276)
			(end -0.802 0.424)
			(stroke
				(width 0.15)
				(type solid)
			)
			(layer "F.Fab")
		)
		(fp_line
			(start -0.652 -0.425)
			(end -0.802 -0.276)
			(stroke
				(width 0.15)
				(type solid)
			)
			(layer "F.Fab")
		)
		(fp_line
			(start 0.8 -0.425)
			(end 0.8 0.424)
			(stroke
				(width 0.15)
				(type solid)
			)
			(layer "F.Fab")
		)
		(fp_line
			(start 0.8 -0.425)
			(end -0.652 -0.425)
			(stroke
				(width 0.15)
				(type solid)
			)
			(layer "F.Fab")
		)
		(fp_circle
			(center -0.9652 0.9652)
			(end -0.9144 0.9652)
			(stroke
				(width 0.15)
				(type solid)
			)
			(fill no)
			(layer "F.Fab")
		)
		(fp_text user "${REFERENCE}"
			(at -1.12 3.824 270)
			(layer "F.Fab")
			(effects
				(font
					(size 0.7 0.7)
					(thickness 0.15)
				)
				(justify left bottom)
			)
		)
		(fp_text user "Author: Antmicro"
			(at -1.12 6.224 270)
			(layer "F.Fab")
			(effects
				(font
					(size 0.7 0.7)
					(thickness 0.15)
				)
				(justify left bottom)
			)
		)
		(fp_text user "License: Apache-2.0"
			(at -1.12 5.024 270)
			(layer "F.Fab")
			(effects
				(font
					(size 0.7 0.7)
					(thickness 0.15)
				)
				(justify left bottom)
			)
		)
		(pad "1" smd rect
			(at -0.5 0.65 270)
			(size 0.4 0.51)
			(layers "F.Cu" "F.Mask" "F.Paste")
			(net 490 "Net-(Q905-G)")
			(pinfunction "G")
			(pintype "input")
		)
		(pad "2" smd rect
			(at 0.498 0.65 270)
			(size 0.4 0.51)
			(layers "F.Cu" "F.Mask" "F.Paste")
			(net 3 "GND")
			(pinfunction "S")
			(pintype "passive")
		)
		(pad "3" smd rect
			(at 0 -0.652 270)
			(size 0.4 0.51)
			(layers "F.Cu" "F.Mask" "F.Paste")
			(net 455 "Net-(Q905-D)")
			(pinfunction "D")
			(pintype "passive")
		)
	)
)
